(kicad_pcb
	(version 20260206)
	(generator "pcbnew")
	(generator_version "10.0")
	(general
		(thickness 1.6)
		(legacy_teardrops no)
	)
	(paper "A4")
	(title_block
		(title "Bryce Canyon_R.DPB_16317-1_OCP.brd")
		(comment 1 "Bryce Canyon / footprints 603-609 of 2099")
	)
	(layers
		(0 "F.Cu" signal "TOP")
		(4 "In1.Cu" signal "L2GND")
		(6 "In2.Cu" signal "L3")
		(8 "In3.Cu" signal "L4VCC")
		(10 "In4.Cu" signal "L5VCC")
		(12 "In5.Cu" signal "L6")
		(14 "In6.Cu" signal "L7GND")
		(2 "B.Cu" signal "BOTTOM")
		(9 "F.Adhes" user "F.Adhesive")
		(11 "B.Adhes" user "B.Adhesive")
		(13 "F.Paste" user "Package Geometry/Pastemask Top")
		(15 "B.Paste" user "Package Geometry/Pastemask Bottom")
		(5 "F.SilkS" user "Ref Des/Silkscreen Top")
		(7 "B.SilkS" user "Ref Des/Silkscreen Bottom")
		(1 "F.Mask" user "Board Geometry/Soldermask Top")
		(3 "B.Mask" user "Board Geometry/Soldermask Bottom")
		(17 "Dwgs.User" user "User.Drawings")
		(19 "Cmts.User" user "User.Comments")
		(21 "Eco1.User" user "User.Eco1")
		(23 "Eco2.User" user "User.Eco2")
		(25 "Edge.Cuts" user "Board Geometry/Outline")
		(27 "Margin" user)
		(31 "F.CrtYd" user "Package Geometry/Place Bound Top")
		(29 "B.CrtYd" user "Package Geometry/Place Bound Bottom")
		(35 "F.Fab" user "Ref Des/Assembly Top")
		(33 "B.Fab" user "Ref Des/Assembly Bottom")
	)
	(footprint ""
		(layer "F.Cu")
		(at 472.899994 -65.39992)
		(property "Reference" "LED24"
			(at 0 0 0)
			(layer "F.SilkS")
			(hide yes)
			(effects
				(font
					(size 1.27 1.27)
				)
			)
		)
		(property "Value" "LED-BY-19-GP"
			(at -2.132076 1.414018 0)
			(unlocked yes)
			(layer "F.Fab")
			(hide yes)
			(effects
				(font
					(size 1.016 1.016)
					(thickness 0.1524)
				)
			)
		)
		(property "Device Type" "LED-1615-4PH26"
			(at -2.132076 -0.109982 0)
			(unlocked yes)
			(layer "F.Fab")
			(hide yes)
			(effects
				(font
					(size 1.016 1.016)
					(thickness 0.1524)
				)
			)
		)
		(duplicate_pad_numbers_are_jumpers no)
		(fp_line
			(start -1.2954 0.254)
			(end -1.2954 1.6002)
			(stroke
				(width 0.508)
				(type default)
			)
			(layer "F.SilkS")
		)
		(fp_line
			(start -1.2954 1.6002)
			(end 1.2954 1.6002)
			(stroke
				(width 0.508)
				(type default)
			)
			(layer "F.SilkS")
		)
		(fp_line
			(start -1.1176 -1.4224)
			(end 1.1176 -1.4224)
			(stroke
				(width 0.1524)
				(type default)
			)
			(layer "F.SilkS")
		)
		(fp_line
			(start -1.1176 1.4224)
			(end -1.1176 -1.4224)
			(stroke
				(width 0.1524)
				(type default)
			)
			(layer "F.SilkS")
		)
		(fp_line
			(start 1.1176 -1.4224)
			(end 1.1176 1.4224)
			(stroke
				(width 0.1524)
				(type default)
			)
			(layer "F.SilkS")
		)
		(fp_line
			(start 1.1176 1.4224)
			(end -1.1176 1.4224)
			(stroke
				(width 0.1524)
				(type default)
			)
			(layer "F.SilkS")
		)
		(fp_line
			(start 1.2954 1.6002)
			(end 1.2954 0.254)
			(stroke
				(width 0.508)
				(type default)
			)
			(layer "F.SilkS")
		)
		(fp_rect
			(start -0.7493 0.8001)
			(end 0.7493 -0.8001)
			(stroke
				(width 0)
				(type default)
			)
			(fill no)
			(layer "F.CrtYd")
		)
		(fp_poly
			(pts
				(xy -1.3716 1.6764) (xy -1.3716 -1.6764) (xy 1.3716 -1.6764) (xy 1.3716 0.0635) (xy 0.7493 0.0635)
				(xy 0.7493 -0.8001) (xy -0.7493 -0.8001) (xy -0.7493 0.8001) (xy 0.7493 0.8001) (xy 0.7493 0.0762)
				(xy 1.3716 0.0762) (xy 1.3716 1.6764)
			)
			(stroke
				(width 0)
				(type default)
			)
			(fill no)
			(layer "F.CrtYd")
		)
		(fp_rect
			(start -1.3716 1.6764)
			(end 1.3716 -1.6764)
			(stroke
				(width 0)
				(type default)
			)
			(fill no)
			(layer "F.Fab")
		)
		(pad "1" smd rect
			(at 0.50038 -0.73025)
			(size 0.7112 0.8636)
			(layers "F.Cu" "F.Mask" "F.Paste")
			(net "DRV_ACT_23")
		)
		(pad "2" smd rect
			(at -0.50038 -0.73025)
			(size 0.7112 0.8636)
			(layers "F.Cu" "F.Mask" "F.Paste")
			(net "FLT_HDD23")
		)
		(pad "3" smd rect
			(at 0.50038 0.73025)
			(size 0.7112 0.8636)
			(layers "F.Cu" "F.Mask" "F.Paste")
			(net "DRV_ACT_23_N")
		)
		(pad "4" smd rect
			(at -0.50038 0.73025)
			(size 0.7112 0.8636)
			(layers "F.Cu" "F.Mask" "F.Paste")
			(net "FLT_HDD23_N")
		)
	)
	(footprint ""
		(layer "F.Cu")
		(at 330.67498 -63.79972)
		(property "Reference" ""
			(at 0 0 0)
			(layer "F.SilkS")
			(hide yes)
			(effects
				(font
					(size 1.27 1.27)
				)
			)
		)
		(property "Value" "*"
			(at -8.398764 -8.057642 0)
			(unlocked yes)
			(layer "F.Fab")
			(hide yes)
			(effects
				(font
					(size 1.016 1.016)
					(thickness 0.1524)
				)
			)
		)
		(duplicate_pad_numbers_are_jumpers no)
		(fp_poly
			(pts
				(arc
					(start 7.3152 0)
					(mid 0 7.3152)
					(end -7.3152 0)
				)
				(arc
					(start -7.3152 -5.9944)
					(mid 0 -13.3096)
					(end 7.3152 -5.9944)
				)
			)
			(stroke
				(width 0)
				(type default)
			)
			(fill no)
			(layer "B.CrtYd")
		)
		(fp_poly
			(pts
				(arc
					(start 7.3152 0)
					(mid 0 7.3152)
					(end -7.3152 0)
				)
				(arc
					(start -7.3152 -5.9944)
					(mid 0 -13.3096)
					(end 7.3152 -5.9944)
				)
			)
			(stroke
				(width 0)
				(type default)
			)
			(fill no)
			(layer "F.CrtYd")
		)
		(fp_poly
			(pts
				(arc
					(start 7.3152 0)
					(mid 0 7.3152)
					(end -7.3152 0)
				)
				(arc
					(start -7.3152 -5.9944)
					(mid 0 -13.3096)
					(end 7.3152 -5.9944)
				)
			)
			(stroke
				(width 0)
				(type default)
			)
			(fill no)
			(layer "B.Fab")
		)
		(fp_poly
			(pts
				(arc
					(start 7.3152 0)
					(mid 0 7.3152)
					(end -7.3152 0)
				)
				(arc
					(start -7.3152 -5.9944)
					(mid 0 -13.3096)
					(end 7.3152 -5.9944)
				)
			)
			(stroke
				(width 0)
				(type default)
			)
			(fill no)
			(layer "F.Fab")
		)
		(pad "1" thru_hole oval
			(at 0 0)
			(size 14.0208 20.0152)
			(drill 0.0254
				(offset 0 -2.9972)
			)
			(layers "*.Cu" "*.Mask")
			(remove_unused_layers no)
			(net "Net_50")
			(clearance -1.002284)
			(thermal_gap 0.1524)
			(padstack
				(mode front_inner_back)
				(layer "Inner"
					(shape custom)
					(size 2.928012 2.928012)
					(options
						(anchor circle)
					)
					(primitives
						(gr_poly
							(pts
								(arc
									(start 4.571746 -2.084324)
									(mid 0.000333 7.430372)
									(end -4.571492 -2.084324)
								)
								(arc
									(start -4.571492 -2.084324)
									(mid -3.570296 -3.611977)
									(end -2.875026 -5.30098)
								)
								(arc
									(start -2.875026 -5.30098)
									(mid 0.000217 -7.43089)
									(end 2.87528 -5.30098)
								)
								(arc
									(start 2.87528 -5.30098)
									(mid 3.570511 -3.611956)
									(end 4.571746 -2.084324)
								)
							)
							(width 0)
							(fill yes)
						)
					)
					(clearance 0.1524)
				)
				(layer "B.Cu"
					(shape oval)
					(size 14.0208 20.0152)
					(offset 0 -2.9972)
					(clearance -1.002284)
				)
			)
		)
		(zone
			(layers "F.Cu" "B.Cu" "In1.Cu" "In2.Cu" "In3.Cu" "In4.Cu" "In5.Cu" "In6.Cu")
			(hatch none 0.5)
			(connect_pads
				(clearance 0)
			)
			(min_thickness 0.25)
			(keepout
				(tracks not_allowed)
				(vias allowed)
				(pads allowed)
				(copperpour not_allowed)
				(footprints allowed)
			)
			(placement
				(enabled no)
				(sheetname "")
			)
			(fill
				(thermal_gap 0.5)
				(thermal_bridge_width 0.5)
				(island_removal_mode 0)
			)
			(polygon
				(pts
					(arc
						(start 323.66458 -69.79412)
						(mid 330.67498 -76.80452)
						(end 337.68538 -69.79412)
					)
					(arc
						(start 337.68538 -63.79972)
						(mid 330.67498 -56.78932)
						(end 323.66458 -63.79972)
					)
				)
			)
		)
	)
	(footprint ""
		(layer "F.Cu")
		(at 129.921 -148.082 -90)
		(property "Reference" "R415"
			(at 0 0 270)
			(layer "F.SilkS")
			(hide yes)
			(effects
				(font
					(size 1.27 1.27)
				)
			)
		)
		(property "Value" "10KR2F-2-GP"
			(at 0.064008 -3.993896 270)
			(unlocked yes)
			(layer "F.Fab")
			(hide yes)
			(effects
				(font
					(size 1.016 1.016)
					(thickness 0.1524)
				)
			)
		)
		(property "Device Type" "R402H16"
			(at 0.064008 -5.517896 270)
			(unlocked yes)
			(layer "F.Fab")
			(hide yes)
			(effects
				(font
					(size 1.016 1.016)
					(thickness 0.1524)
				)
			)
		)
		(duplicate_pad_numbers_are_jumpers no)
		(fp_line
			(start -0.508 -0.9398)
			(end -0.508 0.9398)
			(stroke
				(width 0.1524)
				(type default)
			)
			(layer "F.SilkS")
		)
		(fp_line
			(start 0.508 -0.9398)
			(end -0.508 -0.9398)
			(stroke
				(width 0.1524)
				(type default)
			)
			(layer "F.SilkS")
		)
		(fp_rect
			(start -0.508 0.9398)
			(end 0.508 -0.9398)
			(stroke
				(width 0)
				(type default)
			)
			(fill no)
			(layer "F.CrtYd")
		)
		(fp_rect
			(start -0.508 0.9398)
			(end 0.508 -0.9398)
			(stroke
				(width 0)
				(type default)
			)
			(fill no)
			(layer "F.Fab")
		)
		(pad "1" smd custom
			(at 0 -0.4445 270)
			(size 0.1397 0.1397)
			(layers "F.Cu" "F.Mask" "F.Paste")
			(net "P3V3_STBY_B")
			(options
				(clearance outline)
				(anchor circle)
			)
			(primitives
				(gr_poly
					(pts
						(arc
							(start -0.1778 -0.2794)
							(mid -0.249642 -0.249642)
							(end -0.2794 -0.1778)
						)
						(arc
							(start -0.2794 0.1778)
							(mid -0.249642 0.249642)
							(end -0.1778 0.2794)
						)
						(arc
							(start 0.1778 0.2794)
							(mid 0.249642 0.249642)
							(end 0.2794 0.1778)
						)
						(arc
							(start 0.2794 -0.1778)
							(mid 0.249642 -0.249642)
							(end 0.1778 -0.2794)
						)
					)
					(width 0)
					(fill yes)
				)
			)
		)
		(pad "2" smd custom
			(at 0 0.4445 270)
			(size 0.1397 0.1397)
			(layers "F.Cu" "F.Mask" "F.Paste")
			(net "HDD_PRSNT_15")
			(options
				(clearance outline)
				(anchor circle)
			)
			(primitives
				(gr_poly
					(pts
						(arc
							(start -0.1778 -0.2794)
							(mid -0.249642 -0.249642)
							(end -0.2794 -0.1778)
						)
						(arc
							(start -0.2794 0.1778)
							(mid -0.249642 0.249642)
							(end -0.1778 0.2794)
						)
						(arc
							(start 0.1778 0.2794)
							(mid 0.249642 0.249642)
							(end 0.2794 0.1778)
						)
						(arc
							(start 0.2794 -0.1778)
							(mid 0.249642 -0.249642)
							(end 0.1778 -0.2794)
						)
					)
					(width 0)
					(fill yes)
				)
			)
		)
	)
	(footprint ""
		(layer "F.Cu")
		(at 362.966 -32.004 -90)
		(property "Reference" "R782"
			(at 0 0 270)
			(layer "F.SilkS")
			(hide yes)
			(effects
				(font
					(size 1.27 1.27)
				)
			)
		)
		(property "Value" "2R6F-GP"
			(at -0.0508 -4.8514 270)
			(unlocked yes)
			(layer "F.Fab")
			(hide yes)
			(effects
				(font
					(size 1.016 1.016)
					(thickness 0.1524)
				)
			)
		)
		(property "Device Type" "R1206H26"
			(at 0 -6.3754 270)
			(unlocked yes)
			(layer "F.Fab")
			(hide yes)
			(effects
				(font
					(size 1.016 1.016)
					(thickness 0.1524)
				)
			)
		)
		(duplicate_pad_numbers_are_jumpers no)
		(fp_line
			(start -1.016 2.2352)
			(end -1.016 -2.2352)
			(stroke
				(width 0.1524)
				(type default)
			)
			(layer "F.SilkS")
		)
		(fp_line
			(start 1.016 2.2352)
			(end -1.016 2.2352)
			(stroke
				(width 0.1524)
				(type default)
			)
			(layer "F.SilkS")
		)
		(fp_line
			(start -1.016 -2.2352)
			(end 1.016 -2.2352)
			(stroke
				(width 0.1524)
				(type default)
			)
			(layer "F.SilkS")
		)
		(fp_line
			(start 1.016 -2.2352)
			(end 1.016 2.2352)
			(stroke
				(width 0.1524)
				(type default)
			)
			(layer "F.SilkS")
		)
		(fp_rect
			(start -1.0922 2.3114)
			(end 1.0922 -2.3114)
			(stroke
				(width 0)
				(type default)
			)
			(fill no)
			(layer "F.CrtYd")
		)
		(fp_poly
			(pts
				(xy -1.0922 -2.3114) (xy 1.0922 -2.3114) (xy 1.0922 2.3114) (xy -1.0922 2.3114)
			)
			(stroke
				(width 0)
				(type default)
			)
			(fill no)
			(layer "F.Fab")
		)
		(pad "1" smd rect
			(at 0 -1.397 270)
			(size 1.651 1.27)
			(layers "F.Cu" "F.Mask" "F.Paste")
			(net "P5V_HDD31")
		)
		(pad "2" smd rect
			(at 0 1.397 270)
			(size 1.651 1.27)
			(layers "F.Cu" "F.Mask" "F.Paste")
			(net "5V_PRE_31")
		)
	)
	(footprint ""
		(layer "F.Cu")
		(at 249.921522 -359.257346)
		(property "Reference" "C562"
			(at 0 0 0)
			(layer "F.SilkS")
			(hide yes)
			(effects
				(font
					(size 1.27 1.27)
				)
			)
		)
		(property "Value" "SC1U16V3KX-5GP"
			(at 0 -2.8194 0)
			(unlocked yes)
			(layer "F.Fab")
			(hide yes)
			(effects
				(font
					(size 1.016 1.016)
					(thickness 0.1524)
				)
			)
		)
		(property "Device Type" "C603H36"
			(at 0 -4.3434 0)
			(unlocked yes)
			(layer "F.Fab")
			(hide yes)
			(effects
				(font
					(size 1.016 1.016)
					(thickness 0.1524)
				)
			)
		)
		(duplicate_pad_numbers_are_jumpers no)
		(fp_line
			(start 0.508 0)
			(end -0.508 0)
			(stroke
				(width 0.2032)
				(type default)
			)
			(layer "F.SilkS")
		)
		(fp_rect
			(start -0.5842 1.3335)
			(end 0.5842 -1.3335)
			(stroke
				(width 0)
				(type default)
			)
			(fill no)
			(layer "F.CrtYd")
		)
		(fp_rect
			(start -0.5842 1.3335)
			(end 0.5842 -1.3335)
			(stroke
				(width 0)
				(type default)
			)
			(fill no)
			(layer "F.Fab")
		)
		(pad "1" smd custom
			(at 0 -0.762)
			(size 0.2159 0.2159)
			(layers "F.Cu" "F.Mask" "F.Paste")
			(net "MB3_VCAP_R")
			(options
				(clearance outline)
				(anchor circle)
			)
			(primitives
				(gr_poly
					(pts
						(arc
							(start -0.3302 -0.4318)
							(mid -0.402042 -0.402042)
							(end -0.4318 -0.3302)
						)
						(arc
							(start -0.4318 0.3302)
							(mid -0.402042 0.402042)
							(end -0.3302 0.4318)
						)
						(arc
							(start 0.3302 0.4318)
							(mid 0.402042 0.402042)
							(end 0.4318 0.3302)
						)
						(arc
							(start 0.4318 -0.3302)
							(mid 0.402042 -0.402042)
							(end 0.3302 -0.4318)
						)
					)
					(width 0)
					(fill yes)
				)
			)
		)
		(pad "2" smd custom
			(at 0 0.762)
			(size 0.2159 0.2159)
			(layers "F.Cu" "F.Mask" "F.Paste")
			(net "AGND_CURRENT_DPB")
			(options
				(clearance outline)
				(anchor circle)
			)
			(primitives
				(gr_poly
					(pts
						(arc
							(start -0.3302 -0.4318)
							(mid -0.402042 -0.402042)
							(end -0.4318 -0.3302)
						)
						(arc
							(start -0.4318 0.3302)
							(mid -0.402042 0.402042)
							(end -0.3302 0.4318)
						)
						(arc
							(start 0.3302 0.4318)
							(mid 0.402042 0.402042)
							(end 0.4318 0.3302)
						)
						(arc
							(start 0.4318 -0.3302)
							(mid 0.402042 -0.402042)
							(end 0.3302 -0.4318)
						)
					)
					(width 0)
					(fill yes)
				)
			)
		)
	)
	(footprint ""
		(layer "F.Cu")
		(at 445.102996 -364.263686 90)
		(property "Reference" "C536"
			(at 0 0 90)
			(layer "F.SilkS")
			(hide yes)
			(effects
				(font
					(size 1.27 1.27)
				)
			)
		)
		(property "Value" "SCD1U25V2KX-2-GP"
			(at 1.1811 -2.7051 90)
			(unlocked yes)
			(layer "F.Fab")
			(hide yes)
			(effects
				(font
					(size 1.016 1.016)
					(thickness 0.1524)
				)
			)
		)
		(property "Device Type" "C402H22"
			(at 1.1811 -4.2291 90)
			(unlocked yes)
			(layer "F.Fab")
			(hide yes)
			(effects
				(font
					(size 1.016 1.016)
					(thickness 0.1524)
				)
			)
		)
		(duplicate_pad_numbers_are_jumpers no)
		(fp_rect
			(start -0.4318 0.9525)
			(end 0.4318 -0.9525)
			(stroke
				(width 0)
				(type default)
			)
			(fill no)
			(layer "F.CrtYd")
		)
		(fp_rect
			(start -0.4318 0.9525)
			(end 0.4318 -0.9525)
			(stroke
				(width 0)
				(type default)
			)
			(fill no)
			(layer "F.Fab")
		)
		(pad "1" smd custom
			(at 0 -0.4445 90)
			(size 0.1524 0.1524)
			(layers "F.Cu" "F.Mask" "F.Paste")
			(net "P12V_FAN3")
			(options
				(clearance outline)
				(anchor circle)
			)
			(primitives
				(gr_poly
					(pts
						(arc
							(start 0.3048 -0.2032)
							(mid 0.275042 -0.275042)
							(end 0.2032 -0.3048)
						)
						(arc
							(start -0.2032 -0.3048)
							(mid -0.275042 -0.275042)
							(end -0.3048 -0.2032)
						)
						(arc
							(start -0.3048 0.2032)
							(mid -0.275042 0.275042)
							(end -0.2032 0.3048)
						)
						(arc
							(start 0.2032 0.3048)
							(mid 0.275042 0.275042)
							(end 0.3048 0.2032)
						)
					)
					(width 0)
					(fill yes)
				)
			)
		)
		(pad "2" smd custom
			(at 0 0.4445 90)
			(size 0.1524 0.1524)
			(layers "F.Cu" "F.Mask" "F.Paste")
			(net "GND")
			(options
				(clearance outline)
				(anchor circle)
			)
			(primitives
				(gr_poly
					(pts
						(arc
							(start 0.3048 -0.2032)
							(mid 0.275042 -0.275042)
							(end 0.2032 -0.3048)
						)
						(arc
							(start -0.2032 -0.3048)
							(mid -0.275042 -0.275042)
							(end -0.3048 -0.2032)
						)
						(arc
							(start -0.3048 0.2032)
							(mid -0.275042 0.275042)
							(end -0.2032 0.3048)
						)
						(arc
							(start 0.2032 0.3048)
							(mid 0.275042 0.275042)
							(end 0.3048 0.2032)
						)
					)
					(width 0)
					(fill yes)
				)
			)
		)
	)
	(footprint ""
		(layer "F.Cu")
		(at 257.2893 -213.95944 -90)
		(property "Reference" "C24"
			(at 0 0 270)
			(layer "F.SilkS")
			(hide yes)
			(effects
				(font
					(size 1.27 1.27)
				)
			)
		)
		(property "Value" "SC1U16V3KX-5GP"
			(at 0 -2.8194 270)
			(unlocked yes)
			(layer "F.Fab")
			(hide yes)
			(effects
				(font
					(size 1.016 1.016)
					(thickness 0.1524)
				)
			)
		)
		(property "Device Type" "C603H36"
			(at 0 -4.3434 270)
			(unlocked yes)
			(layer "F.Fab")
			(hide yes)
			(effects
				(font
					(size 1.016 1.016)
					(thickness 0.1524)
				)
			)
		)
		(duplicate_pad_numbers_are_jumpers no)
		(fp_line
			(start 0.508 0)
			(end -0.508 0)
			(stroke
				(width 0.2032)
				(type default)
			)
			(layer "F.SilkS")
		)
		(fp_rect
			(start -0.5842 1.3335)
			(end 0.5842 -1.3335)
			(stroke
				(width 0)
				(type default)
			)
			(fill no)
			(layer "F.CrtYd")
		)
		(fp_rect
			(start -0.5842 1.3335)
			(end 0.5842 -1.3335)
			(stroke
				(width 0)
				(type default)
			)
			(fill no)
			(layer "F.Fab")
		)
		(pad "1" smd custom
			(at 0 -0.762 270)
			(size 0.2159 0.2159)
			(layers "F.Cu" "F.Mask" "F.Paste")
			(net "P3V3_STBY_B")
			(options
				(clearance outline)
				(anchor circle)
			)
			(primitives
				(gr_poly
					(pts
						(arc
							(start -0.3302 -0.4318)
							(mid -0.402042 -0.402042)
							(end -0.4318 -0.3302)
						)
						(arc
							(start -0.4318 0.3302)
							(mid -0.402042 0.402042)
							(end -0.3302 0.4318)
						)
						(arc
							(start 0.3302 0.4318)
							(mid 0.402042 0.402042)
							(end 0.4318 0.3302)
						)
						(arc
							(start 0.4318 -0.3302)
							(mid 0.402042 -0.402042)
							(end 0.3302 -0.4318)
						)
					)
					(width 0)
					(fill yes)
				)
			)
		)
		(pad "2" smd custom
			(at 0 0.762 270)
			(size 0.2159 0.2159)
			(layers "F.Cu" "F.Mask" "F.Paste")
			(net "GND")
			(options
				(clearance outline)
				(anchor circle)
			)
			(primitives
				(gr_poly
					(pts
						(arc
							(start -0.3302 -0.4318)
							(mid -0.402042 -0.402042)
							(end -0.4318 -0.3302)
						)
						(arc
							(start -0.4318 0.3302)
							(mid -0.402042 0.402042)
							(end -0.3302 0.4318)
						)
						(arc
							(start 0.3302 0.4318)
							(mid 0.402042 0.402042)
							(end 0.4318 0.3302)
						)
						(arc
							(start 0.4318 -0.3302)
							(mid 0.402042 -0.402042)
							(end 0.3302 -0.4318)
						)
					)
					(width 0)
					(fill yes)
				)
			)
		)
	)
)
